(kicad_pcb
	(version 20260206)
	(generator "pcbnew")
	(generator_version "10.0")
	(general
		(thickness 1.6)
		(legacy_teardrops no)
	)
	(paper "A4")
	(title_block
		(title "Bryce Canyon_F.DPB_16315-1-OCP.brd")
		(comment 1 "Bryce Canyon / footprint 448 of 2223 (MONO3), pads 74-146 of 166")
	)
	(layers
		(0 "F.Cu" signal "TOP")
		(4 "In1.Cu" signal "L2GND")
		(6 "In2.Cu" signal "L3")
		(8 "In3.Cu" signal "L4GND")
		(10 "In4.Cu" signal "L5")
		(12 "In5.Cu" signal "L6VCC")
		(14 "In6.Cu" signal "L7VCC")
		(16 "In7.Cu" signal "L8")
		(18 "In8.Cu" signal "L9GND")
		(20 "In9.Cu" signal "L10")
		(22 "In10.Cu" signal "L11GND")
		(2 "B.Cu" signal "BOTTOM")
		(9 "F.Adhes" user "F.Adhesive")
		(11 "B.Adhes" user "B.Adhesive")
		(13 "F.Paste" user "Package Geometry/Pastemask Top")
		(15 "B.Paste" user "Package Geometry/Pastemask Bottom")
		(5 "F.SilkS" user "Ref Des/Silkscreen Top")
		(7 "B.SilkS" user "Ref Des/Silkscreen Bottom")
		(1 "F.Mask" user "Board Geometry/Soldermask Top")
		(3 "B.Mask" user "Board Geometry/Soldermask Bottom")
		(17 "Dwgs.User" user "User.Drawings")
		(19 "Cmts.User" user "User.Comments")
		(21 "Eco1.User" user "User.Eco1")
		(23 "Eco2.User" user "User.Eco2")
		(25 "Edge.Cuts" user "Board Geometry/Outline")
		(27 "Margin" user)
		(31 "F.CrtYd" user "Package Geometry/Place Bound Top")
		(29 "B.CrtYd" user "Package Geometry/Place Bound Bottom")
		(35 "F.Fab" user "Ref Des/Assembly Top")
		(33 "B.Fab" user "Ref Des/Assembly Bottom")
	)
	(footprint ""
		(layer "F.Cu")
		(at 281.999944 -111.149892 90)
		(property "Reference" "MONO3"
			(at 0 0 90)
			(layer "F.SilkS")
			(hide yes)
			(effects
				(font
					(size 1.27 1.27)
				)
			)
		)
		(property "Value" "AMP-CONN164-4R-1-GP"
			(at -25.705054 -1.203706 90)
			(unlocked yes)
			(layer "F.Fab")
			(hide yes)
			(effects
				(font
					(size 1.016 1.016)
					(thickness 0.1524)
				)
			)
		)
		(property "Device Type" "PREFIT-164P-890091-1H441"
			(at -25.705054 -2.727706 90)
			(unlocked yes)
			(layer "F.Fab")
			(hide yes)
			(effects
				(font
					(size 1.016 1.016)
					(thickness 0.1524)
				)
			)
		)
		(duplicate_pad_numbers_are_jumpers no)
		(pad "A72" thru_hole circle
			(at 61.34989 -3.24993 90)
			(size 1.0668 1.0668)
			(drill 0.719836)
			(layers "*.Cu" "*.Mask")
			(remove_unused_layers no)
			(net "GND")
			(clearance 0.1905)
			(thermal_gap 0.1905)
		)
		(pad "A73" thru_hole circle
			(at 62.349888 -1.249934 90)
			(size 1.0668 1.0668)
			(drill 0.719836)
			(layers "*.Cu" "*.Mask")
			(remove_unused_layers no)
			(net "PCIE_IOM_B_TO_COMP_B_10_DP")
			(clearance 0.1905)
			(thermal_gap 0.1905)
		)
		(pad "A74" thru_hole circle
			(at 63.349886 -3.24993 90)
			(size 1.0668 1.0668)
			(drill 0.719836)
			(layers "*.Cu" "*.Mask")
			(remove_unused_layers no)
			(net "PCIE_IOM_B_TO_COMP_B_10_DN")
			(clearance 0.1905)
			(thermal_gap 0.1905)
		)
		(pad "A75" thru_hole circle
			(at 64.349884 -1.249934 90)
			(size 1.0668 1.0668)
			(drill 0.719836)
			(layers "*.Cu" "*.Mask")
			(remove_unused_layers no)
			(net "GND")
			(clearance 0.1905)
			(thermal_gap 0.1905)
		)
		(pad "A76" thru_hole circle
			(at 65.349882 -3.24993 90)
			(size 1.0668 1.0668)
			(drill 0.719836)
			(layers "*.Cu" "*.Mask")
			(remove_unused_layers no)
			(net "GND")
			(clearance 0.1905)
			(thermal_gap 0.1905)
		)
		(pad "A77" thru_hole circle
			(at 66.34988 -1.249934 90)
			(size 1.0668 1.0668)
			(drill 0.719836)
			(layers "*.Cu" "*.Mask")
			(remove_unused_layers no)
			(net "PCIE_IOM_B_TO_COMP_B_11_DP")
			(clearance 0.1905)
			(thermal_gap 0.1905)
		)
		(pad "A78" thru_hole circle
			(at 67.349878 -3.24993 90)
			(size 1.0668 1.0668)
			(drill 0.719836)
			(layers "*.Cu" "*.Mask")
			(remove_unused_layers no)
			(net "PCIE_IOM_B_TO_COMP_B_11_DN")
			(clearance 0.1905)
			(thermal_gap 0.1905)
		)
		(pad "A79" thru_hole circle
			(at 68.349876 -1.249934 90)
			(size 1.0668 1.0668)
			(drill 0.719836)
			(layers "*.Cu" "*.Mask")
			(remove_unused_layers no)
			(net "GND")
			(clearance 0.1905)
			(thermal_gap 0.1905)
		)
		(pad "A80" thru_hole circle
			(at 69.349874 -3.24993 90)
			(size 1.0668 1.0668)
			(drill 0.719836)
			(layers "*.Cu" "*.Mask")
			(remove_unused_layers no)
			(net "GND")
			(clearance 0.1905)
			(thermal_gap 0.1905)
		)
		(pad "A81" thru_hole circle
			(at 70.350126 -1.249934 90)
			(size 1.0668 1.0668)
			(drill 0.719836)
			(layers "*.Cu" "*.Mask")
			(remove_unused_layers no)
			(net "P12V_B_COMP")
			(clearance 0.1905)
			(thermal_gap 0.1905)
		)
		(pad "A82" thru_hole circle
			(at 71.350124 -3.24993 90)
			(size 1.0668 1.0668)
			(drill 0.719836)
			(layers "*.Cu" "*.Mask")
			(remove_unused_layers no)
			(net "P12V_B_COMP")
			(clearance 0.1905)
			(thermal_gap 0.1905)
		)
		(pad "B1" thru_hole circle
			(at -11.649964 1.249934 90)
			(size 1.0668 1.0668)
			(drill 0.719836)
			(layers "*.Cu" "*.Mask")
			(remove_unused_layers no)
			(net "P12V_B_COMP")
			(clearance 0.1905)
			(thermal_gap 0.1905)
		)
		(pad "B2" thru_hole circle
			(at -10.649966 3.24993 90)
			(size 1.0668 1.0668)
			(drill 0.719836)
			(layers "*.Cu" "*.Mask")
			(remove_unused_layers no)
			(net "P12V_B_COMP")
			(clearance 0.1905)
			(thermal_gap 0.1905)
		)
		(pad "B3" thru_hole circle
			(at -9.649968 1.249934 90)
			(size 1.0668 1.0668)
			(drill 0.719836)
			(layers "*.Cu" "*.Mask")
			(remove_unused_layers no)
			(net "P12V_B_COMP")
			(clearance 0.1905)
			(thermal_gap 0.1905)
		)
		(pad "B4" thru_hole circle
			(at -8.64997 3.24993 90)
			(size 1.0668 1.0668)
			(drill 0.719836)
			(layers "*.Cu" "*.Mask")
			(remove_unused_layers no)
			(net "GND")
			(clearance 0.1905)
			(thermal_gap 0.1905)
		)
		(pad "B5" thru_hole circle
			(at -7.649972 1.249934 90)
			(size 1.0668 1.0668)
			(drill 0.719836)
			(layers "*.Cu" "*.Mask")
			(remove_unused_layers no)
			(net "I2C_BMC_B_COMP_B_SCL")
			(clearance 0.1905)
			(thermal_gap 0.1905)
		)
		(pad "B6" thru_hole circle
			(at -6.649974 3.24993 90)
			(size 1.0668 1.0668)
			(drill 0.719836)
			(layers "*.Cu" "*.Mask")
			(remove_unused_layers no)
			(net "I2C_BMC_B_COMP_B_SDA")
			(clearance 0.1905)
			(thermal_gap 0.1905)
		)
		(pad "B7" thru_hole circle
			(at -5.649976 1.249934 90)
			(size 1.0668 1.0668)
			(drill 0.719836)
			(layers "*.Cu" "*.Mask")
			(remove_unused_layers no)
			(net "GND")
			(clearance 0.1905)
			(thermal_gap 0.1905)
		)
		(pad "B8" thru_hole circle
			(at -4.649978 3.24993 90)
			(size 1.0668 1.0668)
			(drill 0.719836)
			(layers "*.Cu" "*.Mask")
			(remove_unused_layers no)
			(net "COMP_B_PWR_BTN_N")
			(clearance 0.1905)
			(thermal_gap 0.1905)
		)
		(pad "B9" thru_hole circle
			(at -3.64998 1.249934 90)
			(size 1.0668 1.0668)
			(drill 0.719836)
			(layers "*.Cu" "*.Mask")
			(remove_unused_layers no)
			(net "USB_COMP_B_DP")
			(clearance 0.1905)
			(thermal_gap 0.1905)
		)
		(pad "B10" thru_hole circle
			(at -2.649982 3.24993 90)
			(size 1.0668 1.0668)
			(drill 0.719836)
			(layers "*.Cu" "*.Mask")
			(remove_unused_layers no)
			(net "USB_COMP_B_DN")
			(clearance 0.1905)
			(thermal_gap 0.1905)
		)
		(pad "B11" thru_hole circle
			(at -1.649984 1.249934 90)
			(size 1.0668 1.0668)
			(drill 0.719836)
			(layers "*.Cu" "*.Mask")
			(remove_unused_layers no)
			(net "SYS_B_RESET_BUFFER_N")
			(clearance 0.1905)
			(thermal_gap 0.1905)
		)
		(pad "B12" thru_hole circle
			(at 1.35001 3.24993 90)
			(size 1.0668 1.0668)
			(drill 0.719836)
			(layers "*.Cu" "*.Mask")
			(remove_unused_layers no)
			(net "COMP_B_BMC_B_ALERT_N")
			(clearance 0.1905)
			(thermal_gap 0.1905)
		)
		(pad "B13" thru_hole circle
			(at 2.350008 1.249934 90)
			(size 1.0668 1.0668)
			(drill 0.719836)
			(layers "*.Cu" "*.Mask")
			(remove_unused_layers no)
			(net "GND")
			(clearance 0.1905)
			(thermal_gap 0.1905)
		)
		(pad "B14" thru_hole circle
			(at 3.350006 3.24993 90)
			(size 1.0668 1.0668)
			(drill 0.719836)
			(layers "*.Cu" "*.Mask")
			(remove_unused_layers no)
			(net "GND")
			(clearance 0.1905)
			(thermal_gap 0.1905)
		)
		(pad "B15" thru_hole circle
			(at 4.350004 1.249934 90)
			(size 1.0668 1.0668)
			(drill 0.719836)
			(layers "*.Cu" "*.Mask")
			(remove_unused_layers no)
			(net "PCIE_COMP_B_TO_SCC_B_0_DP")
			(clearance 0.1905)
			(thermal_gap 0.1905)
		)
		(pad "B16" thru_hole circle
			(at 5.350002 3.24993 90)
			(size 1.0668 1.0668)
			(drill 0.719836)
			(layers "*.Cu" "*.Mask")
			(remove_unused_layers no)
			(net "PCIE_COMP_B_TO_SCC_B_0_DN")
			(clearance 0.1905)
			(thermal_gap 0.1905)
		)
		(pad "B17" thru_hole circle
			(at 6.35 1.249934 90)
			(size 1.0668 1.0668)
			(drill 0.719836)
			(layers "*.Cu" "*.Mask")
			(remove_unused_layers no)
			(net "GND")
			(clearance 0.1905)
			(thermal_gap 0.1905)
		)
		(pad "B18" thru_hole circle
			(at 7.349998 3.24993 90)
			(size 1.0668 1.0668)
			(drill 0.719836)
			(layers "*.Cu" "*.Mask")
			(remove_unused_layers no)
			(net "GND")
			(clearance 0.1905)
			(thermal_gap 0.1905)
		)
		(pad "B19" thru_hole circle
			(at 8.349996 1.249934 90)
			(size 1.0668 1.0668)
			(drill 0.719836)
			(layers "*.Cu" "*.Mask")
			(remove_unused_layers no)
			(net "PCIE_COMP_B_TO_SCC_B_1_DP")
			(clearance 0.1905)
			(thermal_gap 0.1905)
		)
		(pad "B20" thru_hole circle
			(at 9.349994 3.24993 90)
			(size 1.0668 1.0668)
			(drill 0.719836)
			(layers "*.Cu" "*.Mask")
			(remove_unused_layers no)
			(net "PCIE_COMP_B_TO_SCC_B_1_DN")
			(clearance 0.1905)
			(thermal_gap 0.1905)
		)
		(pad "B21" thru_hole circle
			(at 10.349992 1.249934 90)
			(size 1.0668 1.0668)
			(drill 0.719836)
			(layers "*.Cu" "*.Mask")
			(remove_unused_layers no)
			(net "GND")
			(clearance 0.1905)
			(thermal_gap 0.1905)
		)
		(pad "B22" thru_hole circle
			(at 11.34999 3.24993 90)
			(size 1.0668 1.0668)
			(drill 0.719836)
			(layers "*.Cu" "*.Mask")
			(remove_unused_layers no)
			(net "GND")
			(clearance 0.1905)
			(thermal_gap 0.1905)
		)
		(pad "B23" thru_hole circle
			(at 12.349988 1.249934 90)
			(size 1.0668 1.0668)
			(drill 0.719836)
			(layers "*.Cu" "*.Mask")
			(remove_unused_layers no)
			(net "PCIE_COMP_B_TO_SCC_B_2_DP")
			(clearance 0.1905)
			(thermal_gap 0.1905)
		)
		(pad "B24" thru_hole circle
			(at 13.349986 3.24993 90)
			(size 1.0668 1.0668)
			(drill 0.719836)
			(layers "*.Cu" "*.Mask")
			(remove_unused_layers no)
			(net "PCIE_COMP_B_TO_SCC_B_2_DN")
			(clearance 0.1905)
			(thermal_gap 0.1905)
		)
		(pad "B25" thru_hole circle
			(at 14.349984 1.249934 90)
			(size 1.0668 1.0668)
			(drill 0.719836)
			(layers "*.Cu" "*.Mask")
			(remove_unused_layers no)
			(net "GND")
			(clearance 0.1905)
			(thermal_gap 0.1905)
		)
		(pad "B26" thru_hole circle
			(at 15.349982 3.24993 90)
			(size 1.0668 1.0668)
			(drill 0.719836)
			(layers "*.Cu" "*.Mask")
			(remove_unused_layers no)
			(net "GND")
			(clearance 0.1905)
			(thermal_gap 0.1905)
		)
		(pad "B27" thru_hole circle
			(at 16.34998 1.249934 90)
			(size 1.0668 1.0668)
			(drill 0.719836)
			(layers "*.Cu" "*.Mask")
			(remove_unused_layers no)
			(net "PCIE_COMP_B_TO_SCC_B_3_DP")
			(clearance 0.1905)
			(thermal_gap 0.1905)
		)
		(pad "B28" thru_hole circle
			(at 17.349978 3.24993 90)
			(size 1.0668 1.0668)
			(drill 0.719836)
			(layers "*.Cu" "*.Mask")
			(remove_unused_layers no)
			(net "PCIE_COMP_B_TO_SCC_B_3_DN")
			(clearance 0.1905)
			(thermal_gap 0.1905)
		)
		(pad "B29" thru_hole circle
			(at 18.349976 1.249934 90)
			(size 1.0668 1.0668)
			(drill 0.719836)
			(layers "*.Cu" "*.Mask")
			(remove_unused_layers no)
			(net "GND")
			(clearance 0.1905)
			(thermal_gap 0.1905)
		)
		(pad "B30" thru_hole circle
			(at 19.349974 3.24993 90)
			(size 1.0668 1.0668)
			(drill 0.719836)
			(layers "*.Cu" "*.Mask")
			(remove_unused_layers no)
			(net "GND")
			(clearance 0.1905)
			(thermal_gap 0.1905)
		)
		(pad "B31" thru_hole circle
			(at 20.349972 1.249934 90)
			(size 1.0668 1.0668)
			(drill 0.719836)
			(layers "*.Cu" "*.Mask")
			(remove_unused_layers no)
			(net "TP_COMP_B_SATA_P0_TX_DP")
			(clearance 0.1905)
			(thermal_gap 0.1905)
		)
		(pad "B32" thru_hole circle
			(at 21.34997 3.24993 90)
			(size 1.0668 1.0668)
			(drill 0.719836)
			(layers "*.Cu" "*.Mask")
			(remove_unused_layers no)
			(net "TP_COMP_B_SATA_P0_TX_DN")
			(clearance 0.1905)
			(thermal_gap 0.1905)
		)
		(pad "B33" thru_hole circle
			(at 22.349968 1.249934 90)
			(size 1.0668 1.0668)
			(drill 0.719836)
			(layers "*.Cu" "*.Mask")
			(remove_unused_layers no)
			(net "GND")
			(clearance 0.1905)
			(thermal_gap 0.1905)
		)
		(pad "B34" thru_hole circle
			(at 23.349966 3.24993 90)
			(size 1.0668 1.0668)
			(drill 0.719836)
			(layers "*.Cu" "*.Mask")
			(remove_unused_layers no)
			(net "GND")
			(clearance 0.1905)
			(thermal_gap 0.1905)
		)
		(pad "B35" thru_hole circle
			(at 24.349964 1.249934 90)
			(size 1.0668 1.0668)
			(drill 0.719836)
			(layers "*.Cu" "*.Mask")
			(remove_unused_layers no)
			(net "TP_PCIE_COMP_B_CLK_1_DP")
			(clearance 0.1905)
			(thermal_gap 0.1905)
		)
		(pad "B36" thru_hole circle
			(at 25.349962 3.24993 90)
			(size 1.0668 1.0668)
			(drill 0.719836)
			(layers "*.Cu" "*.Mask")
			(remove_unused_layers no)
			(net "TP_PCIE_COMP_B_CLK_1_DN")
			(clearance 0.1905)
			(thermal_gap 0.1905)
		)
		(pad "B37" thru_hole circle
			(at 26.34996 1.249934 90)
			(size 1.0668 1.0668)
			(drill 0.719836)
			(layers "*.Cu" "*.Mask")
			(remove_unused_layers no)
			(net "GND")
			(clearance 0.1905)
			(thermal_gap 0.1905)
		)
		(pad "B38" thru_hole circle
			(at 27.349958 3.24993 90)
			(size 1.0668 1.0668)
			(drill 0.719836)
			(layers "*.Cu" "*.Mask")
			(remove_unused_layers no)
			(net "GND")
			(clearance 0.1905)
			(thermal_gap 0.1905)
		)
		(pad "B39" thru_hole circle
			(at 28.349956 1.249934 90)
			(size 1.0668 1.0668)
			(drill 0.719836)
			(layers "*.Cu" "*.Mask")
			(remove_unused_layers no)
			(net "PCIE_COMP_B_PCIE_RST_1")
			(clearance 0.1905)
			(thermal_gap 0.1905)
		)
		(pad "B40" thru_hole circle
			(at 29.349954 3.24993 90)
			(size 1.0668 1.0668)
			(drill 0.719836)
			(layers "*.Cu" "*.Mask")
			(remove_unused_layers no)
			(net "PCIE_COMP_B_TO_IOM_B_RST_2")
			(clearance 0.1905)
			(thermal_gap 0.1905)
		)
		(pad "B41" thru_hole circle
			(at 30.349952 1.249934 90)
			(size 1.0668 1.0668)
			(drill 0.719836)
			(layers "*.Cu" "*.Mask")
			(remove_unused_layers no)
			(net "GND")
			(clearance 0.1905)
			(thermal_gap 0.1905)
		)
		(pad "B42" thru_hole circle
			(at 31.34995 3.24993 90)
			(size 1.0668 1.0668)
			(drill 0.719836)
			(layers "*.Cu" "*.Mask")
			(remove_unused_layers no)
			(net "GND")
			(clearance 0.1905)
			(thermal_gap 0.1905)
		)
		(pad "B43" thru_hole circle
			(at 32.349948 1.249934 90)
			(size 1.0668 1.0668)
			(drill 0.719836)
			(layers "*.Cu" "*.Mask")
			(remove_unused_layers no)
			(net "TP_SMB_COMP_B_NIC_SCL")
			(clearance 0.1905)
			(thermal_gap 0.1905)
		)
		(pad "B44" thru_hole circle
			(at 33.349946 3.24993 90)
			(size 1.0668 1.0668)
			(drill 0.719836)
			(layers "*.Cu" "*.Mask")
			(remove_unused_layers no)
			(net "TP_SMB_COMP_B_NIC_SDA")
			(clearance 0.1905)
			(thermal_gap 0.1905)
		)
		(pad "B45" thru_hole circle
			(at 34.349944 1.249934 90)
			(size 1.0668 1.0668)
			(drill 0.719836)
			(layers "*.Cu" "*.Mask")
			(remove_unused_layers no)
			(net "GND")
			(clearance 0.1905)
			(thermal_gap 0.1905)
		)
		(pad "B46" thru_hole circle
			(at 35.349942 3.24993 90)
			(size 1.0668 1.0668)
			(drill 0.719836)
			(layers "*.Cu" "*.Mask")
			(remove_unused_layers no)
			(net "GND")
			(clearance 0.1905)
			(thermal_gap 0.1905)
		)
		(pad "B47" thru_hole circle
			(at 36.34994 1.249934 90)
			(size 1.0668 1.0668)
			(drill 0.719836)
			(layers "*.Cu" "*.Mask")
			(remove_unused_layers no)
			(net "TP_COMP_B_KR_P0_TX_DP")
			(clearance 0.1905)
			(thermal_gap 0.1905)
		)
		(pad "B48" thru_hole circle
			(at 37.349938 3.24993 90)
			(size 1.0668 1.0668)
			(drill 0.719836)
			(layers "*.Cu" "*.Mask")
			(remove_unused_layers no)
			(net "TP_COMP_B_KR_P0_TX_DN")
			(clearance 0.1905)
			(thermal_gap 0.1905)
		)
		(pad "B49" thru_hole circle
			(at 38.349936 1.249934 90)
			(size 1.0668 1.0668)
			(drill 0.719836)
			(layers "*.Cu" "*.Mask")
			(remove_unused_layers no)
			(net "GND")
			(clearance 0.1905)
			(thermal_gap 0.1905)
		)
		(pad "B50" thru_hole circle
			(at 39.349934 3.24993 90)
			(size 1.0668 1.0668)
			(drill 0.719836)
			(layers "*.Cu" "*.Mask")
			(remove_unused_layers no)
			(net "GND")
			(clearance 0.1905)
			(thermal_gap 0.1905)
		)
		(pad "B51" thru_hole circle
			(at 40.349932 1.249934 90)
			(size 1.0668 1.0668)
			(drill 0.719836)
			(layers "*.Cu" "*.Mask")
			(remove_unused_layers no)
			(net "PCIE_COMP_B_TO_SCC_B_4_DP")
			(clearance 0.1905)
			(thermal_gap 0.1905)
		)
		(pad "B52" thru_hole circle
			(at 41.34993 3.24993 90)
			(size 1.0668 1.0668)
			(drill 0.719836)
			(layers "*.Cu" "*.Mask")
			(remove_unused_layers no)
			(net "PCIE_COMP_B_TO_SCC_B_4_DN")
			(clearance 0.1905)
			(thermal_gap 0.1905)
		)
		(pad "B53" thru_hole circle
			(at 42.349928 1.249934 90)
			(size 1.0668 1.0668)
			(drill 0.719836)
			(layers "*.Cu" "*.Mask")
			(remove_unused_layers no)
			(net "GND")
			(clearance 0.1905)
			(thermal_gap 0.1905)
		)
		(pad "B54" thru_hole circle
			(at 43.349926 3.24993 90)
			(size 1.0668 1.0668)
			(drill 0.719836)
			(layers "*.Cu" "*.Mask")
			(remove_unused_layers no)
			(net "GND")
			(clearance 0.1905)
			(thermal_gap 0.1905)
		)
		(pad "B55" thru_hole circle
			(at 44.349924 1.249934 90)
			(size 1.0668 1.0668)
			(drill 0.719836)
			(layers "*.Cu" "*.Mask")
			(remove_unused_layers no)
			(net "PCIE_COMP_B_TO_SCC_B_5_DP")
			(clearance 0.1905)
			(thermal_gap 0.1905)
		)
		(pad "B56" thru_hole circle
			(at 45.349922 3.24993 90)
			(size 1.0668 1.0668)
			(drill 0.719836)
			(layers "*.Cu" "*.Mask")
			(remove_unused_layers no)
			(net "PCIE_COMP_B_TO_SCC_B_5_DN")
			(clearance 0.1905)
			(thermal_gap 0.1905)
		)
		(pad "B57" thru_hole circle
			(at 46.34992 1.249934 90)
			(size 1.0668 1.0668)
			(drill 0.719836)
			(layers "*.Cu" "*.Mask")
			(remove_unused_layers no)
			(net "GND")
			(clearance 0.1905)
			(thermal_gap 0.1905)
		)
		(pad "B58" thru_hole circle
			(at 47.349918 3.24993 90)
			(size 1.0668 1.0668)
			(drill 0.719836)
			(layers "*.Cu" "*.Mask")
			(remove_unused_layers no)
			(net "GND")
			(clearance 0.1905)
			(thermal_gap 0.1905)
		)
		(pad "B59" thru_hole circle
			(at 48.349916 1.249934 90)
			(size 1.0668 1.0668)
			(drill 0.719836)
			(layers "*.Cu" "*.Mask")
			(remove_unused_layers no)
			(net "PCIE_COMP_B_TO_SCC_B_6_DP")
			(clearance 0.1905)
			(thermal_gap 0.1905)
		)
		(pad "B60" thru_hole circle
			(at 49.349914 3.24993 90)
			(size 1.0668 1.0668)
			(drill 0.719836)
			(layers "*.Cu" "*.Mask")
			(remove_unused_layers no)
			(net "PCIE_COMP_B_TO_SCC_B_6_DN")
			(clearance 0.1905)
			(thermal_gap 0.1905)
		)
		(pad "B61" thru_hole circle
			(at 50.349912 1.249934 90)
			(size 1.0668 1.0668)
			(drill 0.719836)
			(layers "*.Cu" "*.Mask")
			(remove_unused_layers no)
			(net "GND")
			(clearance 0.1905)
			(thermal_gap 0.1905)
		)
		(pad "B62" thru_hole circle
			(at 51.34991 3.24993 90)
			(size 1.0668 1.0668)
			(drill 0.719836)
			(layers "*.Cu" "*.Mask")
			(remove_unused_layers no)
			(net "GND")
			(clearance 0.1905)
			(thermal_gap 0.1905)
		)
	)
)
